# S9S_MB_2U (Grand Teton) — schematic netlist excerpt (pin names and nets, part order shuffled) for the footprints in the layout excerpt that follows; sources: Cadence DE-HDL packaged netlist, KiCad conversion of 03242023_DA0F0TMBIJ0_F0T_Motherboard_J_brd_V01_OCP.brd

J32  SCONN288_ADR50017P087CC  SCONN288_ADR50017-P087CC IO  pkg DDR288S_1-1VXB  page 113
  VIN_BULK0  = P12V_S3_AUX_CPU1_NVDIMM
  RFU0  = TP_CHH_CPU1_DIMM2_FRU_0
  VIN_MGMT  = P3V3_AUX
  HSCL  = I3C_SPD_DDREFGH_CPU1_LVC1_SCL_7
  HSDA  = I3C_SPD_DDREFGH_CPU1_LVC1_SDA
  VSS0  = GND
  DQ0_A  = M_H_CPU1_SA_DQ<0>
  VSS1  = GND
  DQ1_A  = M_H_CPU1_SA_DQ<1>
  VSS2  = GND
  DQS0_A_T  = M_H_CPU1_SA_DQS_DP<0>
  DQS0_A_C  = M_H_CPU1_SA_DQS_DN<0>
  VSS3  = GND
  DQ4_A  = M_H_CPU1_SA_DQ<4>
  VSS4  = GND
  DQ5_A  = M_H_CPU1_SA_DQ<5>
  VSS5  = GND
  DQ8_A  = M_H_CPU1_SA_DQ<8>
  VSS6  = GND
  DQ9_A  = M_H_CPU1_SA_DQ<9>
  VSS7  = GND
  DQS1_A_T  = M_H_CPU1_SA_DQS_DP<1>
  DQS1_A_C  = M_H_CPU1_SA_DQS_DN<1>
  VSS8  = GND
  DQ12_A  = M_H_CPU1_SA_DQ<12>
  VSS9  = GND
  DQ13_A  = M_H_CPU1_SA_DQ<13>
  VSS10  = GND
  DQ16_A  = M_H_CPU1_SA_DQ<16>
  VSS11  = GND
  DQ17_A  = M_H_CPU1_SA_DQ<17>
  VSS12  = GND
  DQS2_A_T  = M_H_CPU1_SA_DQS_DP<2>
  DQS2_A_C  = M_H_CPU1_SA_DQS_DN<2>
  VSS13  = GND
  DQ20_A  = M_H_CPU1_SA_DQ<20>
  VSS14  = GND
  DQ21_A  = M_H_CPU1_SA_DQ<21>
  VSS15  = GND
  DQ24_A  = M_H_CPU1_SA_DQ<24>
  VSS16  = GND
  DQ25_A  = M_H_CPU1_SA_DQ<25>
  VSS17  = GND
  DQS3_A_T  = M_H_CPU1_SA_DQS_DP<3>
  DQS3_A_C  = M_H_CPU1_SA_DQS_DN<3>
  VSS18  = GND
  DQ28_A  = M_H_CPU1_SA_DQ<28>
  VSS19  = GND
  DQ29_A  = M_H_CPU1_SA_DQ<29>
  VSS20  = GND
  CB0_A  = M_H_CPU1_SA_CB<0>
  VSS21  = GND
  CB1_A  = M_H_CPU1_SA_CB<1>
  VSS22  = GND
  DQS4_A_T  = M_H_CPU1_SA_DQS_DP<4>
  DQS4_A_C  = M_H_CPU1_SA_DQS_DN<4>
  VSS23  = GND
  CB4_A  = M_H_CPU1_SA_CB<4>
  VSS24  = GND
  CB5_A  = M_H_CPU1_SA_CB<5>
  VSS25  = GND
  ALERT_N  = M_H_CPU1_ALERT_N
  VSS26  = GND
  CS0_A_N  = M_H_CPU1_SA_CS_N<2>
  VSS27  = GND
  CA0_A  = M_H_CPU1_SA_CA<0>
  VSS28  = GND
  CA2_A  = M_H_CPU1_SA_CA<2>
  VSS29  = GND
  CA4_A  = M_H_CPU1_SA_CA<4>
  VSS30  = GND
  CA6_A  = M_H_CPU1_SA_CA<6>
  VSS31  = GND
  PAR_A  = M_H_CPU1_SA_PAR
  VSS32  = GND
  CA0_B  = M_H_CPU1_SB_CA<0>
  VSS33  = GND
  CA2_B  = M_H_CPU1_SB_CA<2>
  VSS34  = GND
  CA4_B  = M_H_CPU1_SB_CA<4>
  VSS35  = GND
  CA6_B  = M_H_CPU1_SB_CA<6>
  VSS36  = GND
  CS0_B_N  = M_H_CPU1_SB_CS_N<2>
  VSS37  = GND
  \lbd||rsp_a_n\  = M_H_CPU1_SA_RSP<1>
  \lbs||rsp_b_n\  = M_H_CPU1_SB_RSP<1>
  VSS38  = GND
  CB4_B  = M_H_CPU1_SB_CB<4>
  VSS39  = GND
  CB5_B  = M_H_CPU1_SB_CB<5>
  VSS40  = GND
  \dqs9_b_t||tdqs9_b_t||dbi4_b_n\  = M_H_CPU1_SB_DQS_DP<9>
  \dqs9_b_c||tdqs9_b_c\  = M_H_CPU1_SB_DQS_DN<9>
  VSS41  = GND
  CB0_B  = M_H_CPU1_SB_CB<0>
  VSS42  = GND
  CB1_B  = M_H_CPU1_SB_CB<1>
  VSS43  = GND
  DQ0_B  = M_H_CPU1_SB_DQ<0>
  VSS44  = GND
  DQ1_B  = M_H_CPU1_SB_DQ<1>
  VSS45  = GND
  DQS0_B_T  = M_H_CPU1_SB_DQS_DP<0>
  DQS0_B_C  = M_H_CPU1_SB_DQS_DN<0>
  VSS46  = GND
  DQ4_B  = M_H_CPU1_SB_DQ<4>
  VSS47  = GND
  DQ5_B  = M_H_CPU1_SB_DQ<5>
  VSS48  = GND
  DQ8_B  = M_H_CPU1_SB_DQ<8>
  VSS49  = GND
  DQ9_B  = M_H_CPU1_SB_DQ<9>
  VSS50  = GND
  DQS1_B_T  = M_H_CPU1_SB_DQS_DP<1>
  DQS1_B_C  = M_H_CPU1_SB_DQS_DN<1>
  VSS51  = GND
  DQ12_B  = M_H_CPU1_SB_DQ<12>
  VSS52  = GND
  DQ13_B  = M_H_CPU1_SB_DQ<13>
  VSS53  = GND
  DQ16_B  = M_H_CPU1_SB_DQ<16>
  VSS54  = GND
  DQ17_B  = M_H_CPU1_SB_DQ<17>
  VSS55  = GND
  DQS2_B_T  = M_H_CPU1_SB_DQS_DP<2>
  DQS2_B_C  = M_H_CPU1_SB_DQS_DN<2>
  VSS56  = GND
  DQ20_B  = M_H_CPU1_SB_DQ<20>
  VSS57  = GND
  DQ21_B  = M_H_CPU1_SB_DQ<21>
  VSS58  = GND
  DQ24_B  = M_H_CPU1_SB_DQ<24>
  VSS59  = GND
  DQ25_B  = M_H_CPU1_SB_DQ<25>
  VSS60  = GND
  DQS3_B_T  = M_H_CPU1_SB_DQS_DP<3>
  DQS3_B_C  = M_H_CPU1_SB_DQS_DN<3>
  VSS61  = GND
  DQ28_B  = M_H_CPU1_SB_DQ<28>
  VSS62  = GND
  DQ29_B  = M_H_CPU1_SB_DQ<29>
  VSS63  = GND
  RFU1  = TP_CHH_CPU1_DIMM2_FRU_1
  VIN_BULK1  = P12V_S3_AUX_CPU1_NVDIMM
  VIN_BULK2  = P12V_S3_AUX_CPU1_NVDIMM
  \pwr_good||fail_n\  = PWRGD_CHH_CPU1_DIMM2
  HSA  = PD_CHH_CPU1_DIMM2_SAA
  RFU2  = TP_CHH_CPU1_DIMM2_FRU_2
  RFU3  = TP_CHH_CPU1_DIMM2_FRU_3
  VSS64  = GND
  DQ2_A  = M_H_CPU1_SA_DQ<2>
  VSS65  = GND
  DQ3_A  = M_H_CPU1_SA_DQ<3>
  VSS66  = GND
  \dqs5_a_c||tdqs5_a_c||dqs5_a_t||tdqs5_a_t\  = M_H_CPU1_SA_DQS_DN<5>
  \dqs5_a_t||tdqs5_a_t\  = M_H_CPU1_SA_DQS_DP<5>
  VSS67  = GND
  DQ6_A  = M_H_CPU1_SA_DQ<6>
  VSS68  = GND
  DQ7_A  = M_H_CPU1_SA_DQ<7>
  VSS69  = GND
  DQ10_A  = M_H_CPU1_SA_DQ<10>
  VSS70  = GND
  DQ11_A  = M_H_CPU1_SA_DQ<11>
  VSS71  = GND
  \dqs6_a_c||tdqs6_a_c||dqs6_a_t||tdqs6_a_t\  = M_H_CPU1_SA_DQS_DN<6>
  \dqs6_a_t||tdqs6_a_t\  = M_H_CPU1_SA_DQS_DP<6>
  VSS72  = GND
  DQ14_A  = M_H_CPU1_SA_DQ<14>
  VSS73  = GND
  DQ15_A  = M_H_CPU1_SA_DQ<15>
  VSS74  = GND
  DQ18_A  = M_H_CPU1_SA_DQ<18>
  VSS75  = GND
  DQ19_A  = M_H_CPU1_SA_DQ<19>
  VSS76  = GND
  \dqs7_a_c||tdqs7_a_c\  = M_H_CPU1_SA_DQS_DN<7>
  \dqs7_a_t||tdqs7_a_t\  = M_H_CPU1_SA_DQS_DP<7>
  VSS77  = GND
  DQ22_A  = M_H_CPU1_SA_DQ<22>
  VSS78  = GND
  DQ23_A  = M_H_CPU1_SA_DQ<23>
  VSS79  = GND
  DQ26_A  = M_H_CPU1_SA_DQ<26>
  VSS80  = GND
  DQ27_A  = M_H_CPU1_SA_DQ<27>
  VSS81  = GND
  \dqs8_a_c||tdqs8_a_c\  = M_H_CPU1_SA_DQS_DN<8>
  \dqs8_a_t||tdqs8_a_t\  = M_H_CPU1_SA_DQS_DP<8>
  VSS82  = GND
  DQ30_A  = M_H_CPU1_SA_DQ<30>
  VSS83  = GND
  DQ31_A  = M_H_CPU1_SA_DQ<31>
  VSS84  = GND
  CB2_A  = M_H_CPU1_SA_CB<2>
  VSS85  = GND
  CB3_A  = M_H_CPU1_SA_CB<3>
  VSS86  = GND
  \dqs9_a_c||tdqs9_a_c\  = M_H_CPU1_SA_DQS_DN<9>
  \dqs9_a_t||tdqs9_a_t\  = M_H_CPU1_SA_DQS_DP<9>
  VSS87  = GND
  CB6_A  = M_H_CPU1_SA_CB<6>
  VSS88  = GND
  CB7_A  = M_H_CPU1_SA_CB<7>
  VSS89  = GND
  RESET_N  = RST_M_GH_CPU1_FPGA_N
  VSS90  = GND
  CS1_A_N  = M_H_CPU1_SA_CS_N<3>
  VSS91  = GND
  CA1_A  = M_H_CPU1_SA_CA<1>
  VSS92  = GND
  CA3_A  = M_H_CPU1_SA_CA<3>
  VSS93  = GND
  CA5_A  = M_H_CPU1_SA_CA<5>
  VSS94  = GND
  CK_T  = M_H_CPU1_CLK_DP<1>
  CK_C  = M_H_CPU1_CLK_DN<1>
  VSS95  = GND
  RFU4  = TP_CHH_CPU1_DIMM2_FRU_4
  CA1_B  = M_H_CPU1_SB_CA<1>
  VSS96  = GND
  CA3_B  = M_H_CPU1_SB_CA<3>
  VSS97  = GND
  CA5_B  = M_H_CPU1_SB_CA<5>
  VSS98  = GND
  PAR_B  = M_H_CPU1_SB_PAR
  VSS99  = GND
  CS1_B_N  = M_H_CPU1_SB_CS_N<3>
  VSS100  = GND
  RFU5  = TP_CHH_CPU1_DIMM2_FRU_5
  RFU6  = TP_CHH_CPU1_DIMM2_FRU_6
  VSS101  = GND
  CB6_B  = M_H_CPU1_SB_CB<6>
  VSS102  = GND
  CB7_B  = M_H_CPU1_SB_CB<7>
  VSS103  = GND
  DQS4_B_C  = M_H_CPU1_SB_DQS_DN<4>
  DQS4_B_T  = M_H_CPU1_SB_DQS_DP<4>
  VSS104  = GND
  CB2_B  = M_H_CPU1_SB_CB<2>
  VSS105  = GND
  CB3_B  = M_H_CPU1_SB_CB<3>
  VSS106  = GND
  DQ2_B  = M_H_CPU1_SB_DQ<2>
  VSS107  = GND
  DQ3_B  = M_H_CPU1_SB_DQ<3>
  VSS108  = GND
  \dqs5_b_c||tdqs5_b_c\  = M_H_CPU1_SB_DQS_DN<5>
  \dqs5_b_t||tdqs5_b_t\  = M_H_CPU1_SB_DQS_DP<5>
  VSS109  = GND
  DQ6_B  = M_H_CPU1_SB_DQ<6>
  VSS110  = GND
  DQ7_B  = M_H_CPU1_SB_DQ<7>
  VSS111  = GND
  DQ10_B  = M_H_CPU1_SB_DQ<10>
  VSS112  = GND
  DQ11_B  = M_H_CPU1_SB_DQ<11>
  VSS113  = GND
  \dqs6_b_c||tdqs6_b_c\  = M_H_CPU1_SB_DQS_DN<6>
  \dqs6_b_t||tdqs6_b_t\  = M_H_CPU1_SB_DQS_DP<6>
  VSS114  = GND
  DQ14_B  = M_H_CPU1_SB_DQ<14>
  VSS115  = GND
  DQ15_B  = M_H_CPU1_SB_DQ<15>
  VSS116  = GND
  DQ18_B  = M_H_CPU1_SB_DQ<18>
  VSS117  = GND
  DQ19_B  = M_H_CPU1_SB_DQ<19>
  VSS118  = GND
  \dqs7_b_c||tdqs7_b_c\  = M_H_CPU1_SB_DQS_DN<7>
  \dqs7_b_t||tdqs7_b_t\  = M_H_CPU1_SB_DQS_DP<7>
  VSS119  = GND
  DQ22_B  = M_H_CPU1_SB_DQ<22>
  VSS120  = GND
  DQ23_B  = M_H_CPU1_SB_DQ<23>
  VSS121  = GND
  DQ26_B  = M_H_CPU1_SB_DQ<26>
  VSS122  = GND
  DQ27_B  = M_H_CPU1_SB_DQ<27>
  VSS123  = GND
  \dqs8_b_c||tdqs8_b_c\  = M_H_CPU1_SB_DQS_DN<8>
  \dqs8_b_t||tdqs8_b_t\  = M_H_CPU1_SB_DQS_DP<8>
  VSS124  = GND
  DQ30_B  = M_H_CPU1_SB_DQ<30>
  VSS125  = GND
  DQ31_B  = M_H_CPU1_SB_DQ<31>
  VSS126  = GND
  G1  = GND
  G2  = GND
  G3  = GND

(kicad_pcb
	(version 20260206)
	(generator "pcbnew")
	(generator_version "10.0")
	(general
		(thickness 1.6)
		(legacy_teardrops no)
	)
	(paper "A4")
	(title_block
		(title "03242023_DA0F0TMBIJ0_F0T_Motherboard_J_brd_V01_OCP.brd")
		(comment 1 "Grand Teton / footprint 3133 of 6105 (J32), pads 1-45 of 291")
	)
	(layers
		(0 "F.Cu" signal "TOP")
		(4 "In1.Cu" signal "GND")
		(6 "In2.Cu" signal "IN1")
		(8 "In3.Cu" signal "GND1")
		(10 "In4.Cu" signal "IN2")
		(12 "In5.Cu" signal "GND2")
		(14 "In6.Cu" signal "IN3")
		(16 "In7.Cu" signal "GND3")
		(18 "In8.Cu" signal "VCC")
		(20 "In9.Cu" signal "VCC1")
		(22 "In10.Cu" signal "GND4")
		(24 "In11.Cu" signal "IN4")
		(26 "In12.Cu" signal "GND5")
		(28 "In13.Cu" signal "IN5")
		(30 "In14.Cu" signal "GND6")
		(32 "In15.Cu" signal "IN6")
		(34 "In16.Cu" signal "GND7")
		(2 "B.Cu" signal "BOTTOM")
		(9 "F.Adhes" user "F.Adhesive")
		(11 "B.Adhes" user "B.Adhesive")
		(13 "F.Paste" user "Package Geometry/Pastemask Top")
		(15 "B.Paste" user "Package Geometry/Pastemask Bottom")
		(5 "F.SilkS" user "Ref Des/Silkscreen Top")
		(7 "B.SilkS" user "Ref Des/Silkscreen Bottom")
		(1 "F.Mask" user "Board Geometry/Soldermask Top")
		(3 "B.Mask" user "Board Geometry/Soldermask Bottom")
		(17 "Dwgs.User" user "User.Drawings")
		(19 "Cmts.User" user "User.Comments")
		(21 "Eco1.User" user "User.Eco1")
		(23 "Eco2.User" user "User.Eco2")
		(25 "Edge.Cuts" user "Board Geometry/Outline")
		(27 "Margin" user)
		(31 "F.CrtYd" user "Package Geometry/Place Bound Top")
		(29 "B.CrtYd" user "Package Geometry/Place Bound Bottom")
		(35 "F.Fab" user "Ref Des/Assembly Top")
		(33 "B.Fab" user "Ref Des/Assembly Bottom")
	)
	(footprint ""
		(layer "F.Cu")
		(at 206.12608 -258.091686)
		(property "Reference" "J32"
			(at 0.68834 -81.826608 0)
			(unlocked yes)
			(layer "F.SilkS")
			(effects
				(font
					(size 0.7874 0.5842)
					(thickness 0.1524)
				)
				(justify left)
			)
		)
		(property "Value" ""
			(at 0 0 0)
			(layer "F.Fab")
			(effects
				(font
					(size 1.27 1.27)
				)
			)
		)
		(duplicate_pad_numbers_are_jumpers no)
		(pad "1" smd rect
			(at -2.050034 -63.324994 270)
			(size 0.519938 1.4986)
			(layers "F.Cu" "F.Mask" "F.Paste")
			(net "P12V_S3_AUX_CPU1_NVDIMM")
		)
		(pad "2" smd rect
			(at -2.050034 -62.47511 270)
			(size 0.519938 1.4986)
			(layers "F.Cu" "F.Mask" "F.Paste")
			(net "TP_CHH_CPU1_DIMM2_FRU_0")
		)
		(pad "3" smd rect
			(at -2.050034 -61.624972 270)
			(size 0.519938 1.4986)
			(layers "F.Cu" "F.Mask" "F.Paste")
			(net "P3V3_AUX")
		)
		(pad "4" smd rect
			(at -2.050034 -60.775088 270)
			(size 0.519938 1.4986)
			(layers "F.Cu" "F.Mask" "F.Paste")
			(net "I3C_SPD_DDREFGH_CPU1_LVC1_SCL_7")
		)
		(pad "5" smd rect
			(at -2.050034 -59.92495 270)
			(size 0.519938 1.4986)
			(layers "F.Cu" "F.Mask" "F.Paste")
			(net "I3C_SPD_DDREFGH_CPU1_LVC1_SDA")
		)
		(pad "6" smd rect
			(at -2.050034 -59.075066 270)
			(size 0.519938 1.4986)
			(layers "F.Cu" "F.Mask" "F.Paste")
			(net "GND")
		)
		(pad "7" smd rect
			(at -2.050034 -58.224928 270)
			(size 0.519938 1.4986)
			(layers "F.Cu" "F.Mask" "F.Paste")
			(net "M_H_CPU1_SA_DQ<0>")
		)
		(pad "8" smd rect
			(at -2.050034 -57.375044 270)
			(size 0.519938 1.4986)
			(layers "F.Cu" "F.Mask" "F.Paste")
			(net "GND")
		)
		(pad "9" smd rect
			(at -2.050034 -56.524906 270)
			(size 0.519938 1.4986)
			(layers "F.Cu" "F.Mask" "F.Paste")
			(net "M_H_CPU1_SA_DQ<1>")
		)
		(pad "10" smd rect
			(at -2.050034 -55.675022 270)
			(size 0.519938 1.4986)
			(layers "F.Cu" "F.Mask" "F.Paste")
			(net "GND")
		)
		(pad "11" smd rect
			(at -2.050034 -54.824884 270)
			(size 0.519938 1.4986)
			(layers "F.Cu" "F.Mask" "F.Paste")
			(net "M_H_CPU1_SA_DQS_DP<0>")
		)
		(pad "12" smd rect
			(at -2.050034 -53.975 270)
			(size 0.519938 1.4986)
			(layers "F.Cu" "F.Mask" "F.Paste")
			(net "M_H_CPU1_SA_DQS_DN<0>")
		)
		(pad "13" smd rect
			(at -2.050034 -53.125116 270)
			(size 0.519938 1.4986)
			(layers "F.Cu" "F.Mask" "F.Paste")
			(net "GND")
		)
		(pad "14" smd rect
			(at -2.050034 -52.274978 270)
			(size 0.519938 1.4986)
			(layers "F.Cu" "F.Mask" "F.Paste")
			(net "M_H_CPU1_SA_DQ<4>")
		)
		(pad "15" smd rect
			(at -2.050034 -51.425094 270)
			(size 0.519938 1.4986)
			(layers "F.Cu" "F.Mask" "F.Paste")
			(net "GND")
		)
		(pad "16" smd rect
			(at -2.050034 -50.574956 270)
			(size 0.519938 1.4986)
			(layers "F.Cu" "F.Mask" "F.Paste")
			(net "M_H_CPU1_SA_DQ<5>")
		)
		(pad "17" smd rect
			(at -2.050034 -49.725072 270)
			(size 0.519938 1.4986)
			(layers "F.Cu" "F.Mask" "F.Paste")
			(net "GND")
		)
		(pad "18" smd rect
			(at -2.050034 -48.874934 270)
			(size 0.519938 1.4986)
			(layers "F.Cu" "F.Mask" "F.Paste")
			(net "M_H_CPU1_SA_DQ<8>")
		)
		(pad "19" smd rect
			(at -2.050034 -48.02505 270)
			(size 0.519938 1.4986)
			(layers "F.Cu" "F.Mask" "F.Paste")
			(net "GND")
		)
		(pad "20" smd rect
			(at -2.050034 -47.174912 270)
			(size 0.519938 1.4986)
			(layers "F.Cu" "F.Mask" "F.Paste")
			(net "M_H_CPU1_SA_DQ<9>")
		)
		(pad "21" smd rect
			(at -2.050034 -46.325028 270)
			(size 0.519938 1.4986)
			(layers "F.Cu" "F.Mask" "F.Paste")
			(net "GND")
		)
		(pad "22" smd rect
			(at -2.050034 -45.47489 270)
			(size 0.519938 1.4986)
			(layers "F.Cu" "F.Mask" "F.Paste")
			(net "M_H_CPU1_SA_DQS_DP<1>")
		)
		(pad "23" smd rect
			(at -2.050034 -44.625006 270)
			(size 0.519938 1.4986)
			(layers "F.Cu" "F.Mask" "F.Paste")
			(net "M_H_CPU1_SA_DQS_DN<1>")
		)
		(pad "24" smd rect
			(at -2.050034 -43.775122 270)
			(size 0.519938 1.4986)
			(layers "F.Cu" "F.Mask" "F.Paste")
			(net "GND")
		)
		(pad "25" smd rect
			(at -2.050034 -42.924984 270)
			(size 0.519938 1.4986)
			(layers "F.Cu" "F.Mask" "F.Paste")
			(net "M_H_CPU1_SA_DQ<12>")
		)
		(pad "26" smd rect
			(at -2.050034 -42.0751 270)
			(size 0.519938 1.4986)
			(layers "F.Cu" "F.Mask" "F.Paste")
			(net "GND")
		)
		(pad "27" smd rect
			(at -2.050034 -41.224962 270)
			(size 0.519938 1.4986)
			(layers "F.Cu" "F.Mask" "F.Paste")
			(net "M_H_CPU1_SA_DQ<13>")
		)
		(pad "28" smd rect
			(at -2.050034 -40.375078 270)
			(size 0.519938 1.4986)
			(layers "F.Cu" "F.Mask" "F.Paste")
			(net "GND")
		)
		(pad "29" smd rect
			(at -2.050034 -39.52494 270)
			(size 0.519938 1.4986)
			(layers "F.Cu" "F.Mask" "F.Paste")
			(net "M_H_CPU1_SA_DQ<16>")
		)
		(pad "30" smd rect
			(at -2.050034 -38.675056 270)
			(size 0.519938 1.4986)
			(layers "F.Cu" "F.Mask" "F.Paste")
			(net "GND")
		)
		(pad "31" smd rect
			(at -2.050034 -37.824918 270)
			(size 0.519938 1.4986)
			(layers "F.Cu" "F.Mask" "F.Paste")
			(net "M_H_CPU1_SA_DQ<17>")
		)
		(pad "32" smd rect
			(at -2.050034 -36.975034 270)
			(size 0.519938 1.4986)
			(layers "F.Cu" "F.Mask" "F.Paste")
			(net "GND")
		)
		(pad "33" smd rect
			(at -2.050034 -36.124896 270)
			(size 0.519938 1.4986)
			(layers "F.Cu" "F.Mask" "F.Paste")
			(net "M_H_CPU1_SA_DQS_DP<2>")
		)
		(pad "34" smd rect
			(at -2.050034 -35.275012 270)
			(size 0.519938 1.4986)
			(layers "F.Cu" "F.Mask" "F.Paste")
			(net "M_H_CPU1_SA_DQS_DN<2>")
		)
		(pad "35" smd rect
			(at -2.050034 -34.425128 270)
			(size 0.519938 1.4986)
			(layers "F.Cu" "F.Mask" "F.Paste")
			(net "GND")
		)
		(pad "36" smd rect
			(at -2.050034 -33.57499 270)
			(size 0.519938 1.4986)
			(layers "F.Cu" "F.Mask" "F.Paste")
			(net "M_H_CPU1_SA_DQ<20>")
		)
		(pad "37" smd rect
			(at -2.050034 -32.725106 270)
			(size 0.519938 1.4986)
			(layers "F.Cu" "F.Mask" "F.Paste")
			(net "GND")
		)
		(pad "38" smd rect
			(at -2.050034 -31.874968 270)
			(size 0.519938 1.4986)
			(layers "F.Cu" "F.Mask" "F.Paste")
			(net "M_H_CPU1_SA_DQ<21>")
		)
		(pad "39" smd rect
			(at -2.050034 -31.025084 270)
			(size 0.519938 1.4986)
			(layers "F.Cu" "F.Mask" "F.Paste")
			(net "GND")
		)
		(pad "40" smd rect
			(at -2.050034 -30.174946 270)
			(size 0.519938 1.4986)
			(layers "F.Cu" "F.Mask" "F.Paste")
			(net "M_H_CPU1_SA_DQ<24>")
		)
		(pad "41" smd rect
			(at -2.050034 -29.325062 270)
			(size 0.519938 1.4986)
			(layers "F.Cu" "F.Mask" "F.Paste")
			(net "GND")
		)
		(pad "42" smd rect
			(at -2.050034 -28.474924 270)
			(size 0.519938 1.4986)
			(layers "F.Cu" "F.Mask" "F.Paste")
			(net "M_H_CPU1_SA_DQ<25>")
		)
		(pad "43" smd rect
			(at -2.050034 -27.62504 270)
			(size 0.519938 1.4986)
			(layers "F.Cu" "F.Mask" "F.Paste")
			(net "GND")
		)
		(pad "44" smd rect
			(at -2.050034 -26.774902 270)
			(size 0.519938 1.4986)
			(layers "F.Cu" "F.Mask" "F.Paste")
			(net "M_H_CPU1_SA_DQS_DP<3>")
		)
		(pad "45" smd rect
			(at -2.050034 -25.925018 270)
			(size 0.519938 1.4986)
			(layers "F.Cu" "F.Mask" "F.Paste")
			(net "M_H_CPU1_SA_DQS_DN<3>")
		)
	)
)
